(kicad_pcb
	(version 20260206)
	(generator "pcbnew")
	(generator_version "10.0")
	(general
		(thickness 1.6)
		(legacy_teardrops no)
	)
	(paper "A4")
	(title_block
		(title "panther-plus-userver — 13130-1b_20150205.brd")
		(comment 1 "Honey Badger (Wiwynn) / footprints 181-189 of 1509")
	)
	(layers
		(0 "F.Cu" signal "TOP")
		(4 "In1.Cu" signal "L2")
		(6 "In2.Cu" signal "L3")
		(8 "In3.Cu" signal "L4")
		(10 "In4.Cu" signal "L5")
		(12 "In5.Cu" signal "L6")
		(14 "In6.Cu" signal "L7")
		(16 "In7.Cu" signal "L8")
		(18 "In8.Cu" signal "L9")
		(20 "In9.Cu" signal "L10")
		(22 "In10.Cu" signal "L11")
		(2 "B.Cu" signal "BOTTOM")
		(9 "F.Adhes" user "F.Adhesive")
		(11 "B.Adhes" user "B.Adhesive")
		(13 "F.Paste" user "Package Geometry/Pastemask Top")
		(15 "B.Paste" user "Package Geometry/Pastemask Bottom")
		(5 "F.SilkS" user "Ref Des/Silkscreen Top")
		(7 "B.SilkS" user "Ref Des/Silkscreen Bottom")
		(1 "F.Mask" user "Board Geometry/Soldermask Top")
		(3 "B.Mask" user "Board Geometry/Soldermask Bottom")
		(17 "Dwgs.User" user "User.Drawings")
		(19 "Cmts.User" user "User.Comments")
		(21 "Eco1.User" user "User.Eco1")
		(23 "Eco2.User" user "User.Eco2")
		(25 "Edge.Cuts" user "Board Geometry/Outline")
		(27 "Margin" user)
		(31 "F.CrtYd" user "Package Geometry/Place Bound Top")
		(29 "B.CrtYd" user "Package Geometry/Place Bound Bottom")
		(35 "F.Fab" user "Ref Des/Assembly Top")
		(33 "B.Fab" user "Ref Des/Assembly Bottom")
	)
	(footprint ""
		(layer "F.Cu")
		(at 61.849 -63.754 180)
		(property "Reference" "PC38"
			(at 0 0 180)
			(layer "F.SilkS")
			(hide yes)
			(effects
				(font
					(size 1.27 1.27)
				)
			)
		)
		(property "Value" "SC47U6D3V5MX-1-GP"
			(at -0.0762 -6.1214 180)
			(unlocked yes)
			(layer "F.Fab")
			(hide yes)
			(effects
				(font
					(size 1.016 1.016)
					(thickness 0.1524)
				)
			)
		)
		(property "Device Type" "C805H54"
			(at -0.0762 -8.1534 180)
			(unlocked yes)
			(layer "F.Fab")
			(hide yes)
			(effects
				(font
					(size 1.016 1.016)
					(thickness 0.1524)
				)
			)
		)
		(duplicate_pad_numbers_are_jumpers no)
		(fp_line
			(start 0.6096 0)
			(end -0.6096 0)
			(stroke
				(width 0.3048)
				(type default)
			)
			(layer "F.SilkS")
		)
		(fp_poly
			(pts
				(xy -0.9017 1.4351) (xy 0.9017 1.4351) (xy 0.9017 -1.4351) (xy -0.9017 -1.4351)
			)
			(stroke
				(width 0)
				(type default)
			)
			(fill no)
			(layer "F.CrtYd")
		)
		(fp_poly
			(pts
				(xy 0.9017 1.4351) (xy 0.9017 -1.4351) (xy -0.9017 -1.4351) (xy -0.9017 1.4351)
			)
			(stroke
				(width 0)
				(type default)
			)
			(fill no)
			(layer "F.Fab")
		)
		(pad "1" smd rect
			(at 0 -0.8382 180)
			(size 1.5494 0.9398)
			(layers "F.Cu" "F.Mask" "F.Paste")
			(net "PVCCP")
		)
		(pad "2" smd rect
			(at 0 0.8382 180)
			(size 1.5494 0.9398)
			(layers "F.Cu" "F.Mask" "F.Paste")
			(net "GND")
		)
	)
	(footprint ""
		(layer "F.Cu")
		(at 15.8496 -58.3692 -90)
		(property "Reference" "PR56"
			(at 0 0 270)
			(layer "F.SilkS")
			(hide yes)
			(effects
				(font
					(size 1.27 1.27)
				)
			)
		)
		(property "Value" "0R2J-2-GP"
			(at 1.7907 -1.1176 270)
			(unlocked yes)
			(layer "F.Fab")
			(hide yes)
			(effects
				(font
					(size 1.016 1.016)
					(thickness 0.1524)
				)
			)
		)
		(property "Device Type" "R402H16"
			(at 1.7907 -2.6416 270)
			(unlocked yes)
			(layer "F.Fab")
			(hide yes)
			(effects
				(font
					(size 1.016 1.016)
					(thickness 0.1524)
				)
			)
		)
		(duplicate_pad_numbers_are_jumpers no)
		(fp_rect
			(start -0.381 0.8382)
			(end 0.381 -0.8382)
			(stroke
				(width 0)
				(type default)
			)
			(fill no)
			(layer "F.CrtYd")
		)
		(fp_rect
			(start -0.381 0.8382)
			(end 0.381 -0.8382)
			(stroke
				(width 0)
				(type default)
			)
			(fill no)
			(layer "F.Fab")
		)
		(pad "1" smd custom
			(at 0 -0.4318 270)
			(size 0.127 0.127)
			(layers "F.Cu" "F.Mask" "F.Paste")
			(net "PVCC_PVNN_EN_R")
			(options
				(clearance outline)
				(anchor circle)
			)
			(primitives
				(gr_poly
					(pts
						(arc
							(start -0.2032 -0.2794)
							(mid -0.239121 -0.264521)
							(end -0.254 -0.2286)
						)
						(arc
							(start -0.254 0.2286)
							(mid -0.239121 0.264521)
							(end -0.2032 0.2794)
						)
						(arc
							(start 0.2032 0.2794)
							(mid 0.239121 0.264521)
							(end 0.254 0.2286)
						)
						(arc
							(start 0.254 -0.2286)
							(mid 0.239121 -0.264521)
							(end 0.2032 -0.2794)
						)
					)
					(width 0)
					(fill yes)
				)
			)
		)
		(pad "2" smd custom
			(at 0 0.4318 270)
			(size 0.127 0.127)
			(layers "F.Cu" "F.Mask" "F.Paste")
			(net "PMU_SLP_S3#")
			(options
				(clearance outline)
				(anchor circle)
			)
			(primitives
				(gr_poly
					(pts
						(arc
							(start -0.2032 -0.2794)
							(mid -0.239121 -0.264521)
							(end -0.254 -0.2286)
						)
						(arc
							(start -0.254 0.2286)
							(mid -0.239121 0.264521)
							(end -0.2032 0.2794)
						)
						(arc
							(start 0.2032 0.2794)
							(mid 0.239121 0.264521)
							(end 0.254 0.2286)
						)
						(arc
							(start 0.254 -0.2286)
							(mid 0.239121 -0.264521)
							(end 0.2032 -0.2794)
						)
					)
					(width 0)
					(fill yes)
				)
			)
		)
	)
	(footprint ""
		(layer "F.Cu")
		(at 13.716 -31.877)
		(property "Reference" "PC173"
			(at 0 0 0)
			(layer "F.SilkS")
			(hide yes)
			(effects
				(font
					(size 1.27 1.27)
				)
			)
		)
		(property "Value" "SC1U10V2KX-1GP"
			(at 1.8923 -1.2065 0)
			(unlocked yes)
			(layer "F.Fab")
			(hide yes)
			(effects
				(font
					(size 1.016 1.016)
					(thickness 0.1524)
				)
			)
		)
		(property "Device Type" "C402H22"
			(at 1.8923 -2.7305 0)
			(unlocked yes)
			(layer "F.Fab")
			(hide yes)
			(effects
				(font
					(size 1.016 1.016)
					(thickness 0.1524)
				)
			)
		)
		(duplicate_pad_numbers_are_jumpers no)
		(fp_rect
			(start -0.381 0.7366)
			(end 0.381 -0.7366)
			(stroke
				(width 0)
				(type default)
			)
			(fill no)
			(layer "F.CrtYd")
		)
		(fp_rect
			(start -0.381 0.7366)
			(end 0.381 -0.7366)
			(stroke
				(width 0)
				(type default)
			)
			(fill no)
			(layer "F.Fab")
		)
		(pad "1" smd custom
			(at 0 -0.4572)
			(size 0.1143 0.1143)
			(layers "F.Cu" "F.Mask" "F.Paste")
			(net "P3V3_STBY_VFB")
			(options
				(clearance outline)
				(anchor circle)
			)
			(primitives
				(gr_poly
					(pts
						(arc
							(start -0.254 -0.1778)
							(mid -0.239121 -0.213721)
							(end -0.2032 -0.2286)
						)
						(arc
							(start 0.2032 -0.2286)
							(mid 0.239121 -0.213721)
							(end 0.254 -0.1778)
						)
						(arc
							(start 0.254 0.1778)
							(mid 0.239121 0.213721)
							(end 0.2032 0.2286)
						)
						(arc
							(start -0.2032 0.2286)
							(mid -0.239121 0.213721)
							(end -0.254 0.1778)
						)
					)
					(width 0)
					(fill yes)
				)
			)
		)
		(pad "2" smd custom
			(at 0 0.4572)
			(size 0.1143 0.1143)
			(layers "F.Cu" "F.Mask" "F.Paste")
			(net "AGND_P3V3_STBY")
			(options
				(clearance outline)
				(anchor circle)
			)
			(primitives
				(gr_poly
					(pts
						(arc
							(start -0.254 -0.1778)
							(mid -0.239121 -0.213721)
							(end -0.2032 -0.2286)
						)
						(arc
							(start 0.2032 -0.2286)
							(mid 0.239121 -0.213721)
							(end 0.254 -0.1778)
						)
						(arc
							(start 0.254 0.1778)
							(mid 0.239121 0.213721)
							(end 0.2032 0.2286)
						)
						(arc
							(start -0.2032 0.2286)
							(mid -0.239121 0.213721)
							(end -0.254 0.1778)
						)
					)
					(width 0)
					(fill yes)
				)
			)
		)
	)
	(footprint ""
		(layer "F.Cu")
		(at 109.218984 -58.944002 90)
		(property "Reference" "R21"
			(at 0 0 90)
			(layer "F.SilkS")
			(hide yes)
			(effects
				(font
					(size 1.27 1.27)
				)
			)
		)
		(property "Value" "100R3F-1-GP"
			(at -0.0254 -2.5146 90)
			(unlocked yes)
			(layer "F.Fab")
			(hide yes)
			(effects
				(font
					(size 1.016 1.016)
					(thickness 0.1524)
				)
			)
		)
		(property "Device Type" "R603H22"
			(at -0.0254 -4.0386 90)
			(unlocked yes)
			(layer "F.Fab")
			(hide yes)
			(effects
				(font
					(size 1.016 1.016)
					(thickness 0.1524)
				)
			)
		)
		(duplicate_pad_numbers_are_jumpers no)
		(fp_line
			(start 0.4318 0)
			(end 0.2032 0)
			(stroke
				(width 0.2032)
				(type default)
			)
			(layer "F.SilkS")
		)
		(fp_line
			(start -0.2032 0)
			(end -0.4191 0)
			(stroke
				(width 0.2032)
				(type default)
			)
			(layer "F.SilkS")
		)
		(fp_rect
			(start -0.635 1.1811)
			(end 0.635 -1.1811)
			(stroke
				(width 0)
				(type default)
			)
			(fill no)
			(layer "F.CrtYd")
		)
		(fp_rect
			(start -0.635 1.1811)
			(end 0.635 -1.1811)
			(stroke
				(width 0)
				(type default)
			)
			(fill no)
			(layer "F.Fab")
		)
		(pad "1" smd custom
			(at 0 -0.6604 90)
			(size 0.19685 0.19685)
			(layers "F.Cu" "F.Mask" "F.Paste")
			(net "M_A_MON1_P")
			(options
				(clearance outline)
				(anchor circle)
			)
			(primitives
				(gr_poly
					(pts
						(arc
							(start 0.508 -0.2921)
							(mid 0.478242 -0.363942)
							(end 0.4064 -0.3937)
						)
						(arc
							(start -0.4064 -0.3937)
							(mid -0.478242 -0.363942)
							(end -0.508 -0.2921)
						)
						(arc
							(start -0.508 0.2921)
							(mid -0.478242 0.363942)
							(end -0.4064 0.3937)
						)
						(arc
							(start 0.4064 0.3937)
							(mid 0.478242 0.363942)
							(end 0.508 0.2921)
						)
					)
					(width 0)
					(fill yes)
				)
			)
		)
		(pad "2" smd custom
			(at 0 0.6604 90)
			(size 0.19685 0.19685)
			(layers "F.Cu" "F.Mask" "F.Paste")
			(net "M_A_MON1_N")
			(options
				(clearance outline)
				(anchor circle)
			)
			(primitives
				(gr_poly
					(pts
						(arc
							(start 0.508 -0.2921)
							(mid 0.478242 -0.363942)
							(end 0.4064 -0.3937)
						)
						(arc
							(start -0.4064 -0.3937)
							(mid -0.478242 -0.363942)
							(end -0.508 -0.2921)
						)
						(arc
							(start -0.508 0.2921)
							(mid -0.478242 0.363942)
							(end -0.4064 0.3937)
						)
						(arc
							(start 0.4064 0.3937)
							(mid 0.478242 0.363942)
							(end 0.508 0.2921)
						)
					)
					(width 0)
					(fill yes)
				)
			)
		)
	)
	(footprint ""
		(layer "F.Cu")
		(at 183.134 -36.068)
		(property "Reference" "C38"
			(at 0 0 0)
			(layer "F.SilkS")
			(hide yes)
			(effects
				(font
					(size 1.27 1.27)
				)
			)
		)
		(property "Value" "SC1KP50V2KX-1GP"
			(at 1.8923 -1.2065 0)
			(unlocked yes)
			(layer "F.Fab")
			(hide yes)
			(effects
				(font
					(size 1.016 1.016)
					(thickness 0.1524)
				)
			)
		)
		(property "Device Type" "C402H22"
			(at 1.8923 -2.7305 0)
			(unlocked yes)
			(layer "F.Fab")
			(hide yes)
			(effects
				(font
					(size 1.016 1.016)
					(thickness 0.1524)
				)
			)
		)
		(duplicate_pad_numbers_are_jumpers no)
		(fp_rect
			(start -0.381 0.7366)
			(end 0.381 -0.7366)
			(stroke
				(width 0)
				(type default)
			)
			(fill no)
			(layer "F.CrtYd")
		)
		(fp_rect
			(start -0.381 0.7366)
			(end 0.381 -0.7366)
			(stroke
				(width 0)
				(type default)
			)
			(fill no)
			(layer "F.Fab")
		)
		(pad "1" smd custom
			(at 0 -0.4572)
			(size 0.1143 0.1143)
			(layers "F.Cu" "F.Mask" "F.Paste")
			(net "VR_PWREN_PVDDR_A")
			(options
				(clearance outline)
				(anchor circle)
			)
			(primitives
				(gr_poly
					(pts
						(arc
							(start -0.254 -0.1778)
							(mid -0.239121 -0.213721)
							(end -0.2032 -0.2286)
						)
						(arc
							(start 0.2032 -0.2286)
							(mid 0.239121 -0.213721)
							(end 0.254 -0.1778)
						)
						(arc
							(start 0.254 0.1778)
							(mid 0.239121 0.213721)
							(end 0.2032 0.2286)
						)
						(arc
							(start -0.2032 0.2286)
							(mid -0.239121 0.213721)
							(end -0.254 0.1778)
						)
					)
					(width 0)
					(fill yes)
				)
			)
		)
		(pad "2" smd custom
			(at 0 0.4572)
			(size 0.1143 0.1143)
			(layers "F.Cu" "F.Mask" "F.Paste")
			(net "GND")
			(options
				(clearance outline)
				(anchor circle)
			)
			(primitives
				(gr_poly
					(pts
						(arc
							(start -0.254 -0.1778)
							(mid -0.239121 -0.213721)
							(end -0.2032 -0.2286)
						)
						(arc
							(start 0.2032 -0.2286)
							(mid 0.239121 -0.213721)
							(end 0.254 -0.1778)
						)
						(arc
							(start 0.254 0.1778)
							(mid 0.239121 0.213721)
							(end 0.2032 0.2286)
						)
						(arc
							(start -0.2032 0.2286)
							(mid -0.239121 0.213721)
							(end -0.254 0.1778)
						)
					)
					(width 0)
					(fill yes)
				)
			)
		)
	)
	(footprint ""
		(layer "F.Cu")
		(at 187.833 -27.0002 180)
		(property "Reference" "PR161"
			(at 0 0 180)
			(layer "F.SilkS")
			(hide yes)
			(effects
				(font
					(size 1.27 1.27)
				)
			)
		)
		(property "Value" "4K99R2F-L-GP"
			(at 1.7907 -1.1176 180)
			(unlocked yes)
			(layer "F.Fab")
			(hide yes)
			(effects
				(font
					(size 1.016 1.016)
					(thickness 0.1524)
				)
			)
		)
		(property "Device Type" "R402H16"
			(at 1.7907 -2.6416 180)
			(unlocked yes)
			(layer "F.Fab")
			(hide yes)
			(effects
				(font
					(size 1.016 1.016)
					(thickness 0.1524)
				)
			)
		)
		(duplicate_pad_numbers_are_jumpers no)
		(fp_rect
			(start -0.381 0.8382)
			(end 0.381 -0.8382)
			(stroke
				(width 0)
				(type default)
			)
			(fill no)
			(layer "F.CrtYd")
		)
		(fp_rect
			(start -0.381 0.8382)
			(end 0.381 -0.8382)
			(stroke
				(width 0)
				(type default)
			)
			(fill no)
			(layer "F.Fab")
		)
		(pad "1" smd custom
			(at 0 -0.4318 180)
			(size 0.127 0.127)
			(layers "F.Cu" "F.Mask" "F.Paste")
			(net "VSENSE_PVDDR_A_VSEN")
			(options
				(clearance outline)
				(anchor circle)
			)
			(primitives
				(gr_poly
					(pts
						(arc
							(start -0.2032 -0.2794)
							(mid -0.239121 -0.264521)
							(end -0.254 -0.2286)
						)
						(arc
							(start -0.254 0.2286)
							(mid -0.239121 0.264521)
							(end -0.2032 0.2794)
						)
						(arc
							(start 0.2032 0.2794)
							(mid 0.239121 0.264521)
							(end 0.254 0.2286)
						)
						(arc
							(start 0.254 -0.2286)
							(mid 0.239121 -0.264521)
							(end 0.2032 -0.2794)
						)
					)
					(width 0)
					(fill yes)
				)
			)
		)
		(pad "2" smd custom
			(at 0 0.4318 180)
			(size 0.127 0.127)
			(layers "F.Cu" "F.Mask" "F.Paste")
			(net "VSENSE_PVDDR_A_VRTN")
			(options
				(clearance outline)
				(anchor circle)
			)
			(primitives
				(gr_poly
					(pts
						(arc
							(start -0.2032 -0.2794)
							(mid -0.239121 -0.264521)
							(end -0.254 -0.2286)
						)
						(arc
							(start -0.254 0.2286)
							(mid -0.239121 0.264521)
							(end -0.2032 0.2794)
						)
						(arc
							(start 0.2032 0.2794)
							(mid 0.239121 0.264521)
							(end 0.254 0.2286)
						)
						(arc
							(start 0.254 -0.2286)
							(mid 0.239121 -0.264521)
							(end 0.2032 -0.2794)
						)
					)
					(width 0)
					(fill yes)
				)
			)
		)
	)
	(footprint ""
		(layer "F.Cu")
		(at 77.978 -13.716 90)
		(property "Reference" "R193"
			(at 0 0 90)
			(layer "F.SilkS")
			(hide yes)
			(effects
				(font
					(size 1.27 1.27)
				)
			)
		)
		(property "Value" "0R2J-2-GP"
			(at 0.064008 -3.993896 90)
			(unlocked yes)
			(layer "F.Fab")
			(hide yes)
			(effects
				(font
					(size 1.016 1.016)
					(thickness 0.1524)
				)
			)
		)
		(property "Device Type" "R402H16"
			(at 0.064008 -5.517896 90)
			(unlocked yes)
			(layer "F.Fab")
			(hide yes)
			(effects
				(font
					(size 1.016 1.016)
					(thickness 0.1524)
				)
			)
		)
		(duplicate_pad_numbers_are_jumpers no)
		(fp_rect
			(start -0.381 0.8382)
			(end 0.381 -0.8382)
			(stroke
				(width 0)
				(type default)
			)
			(fill no)
			(layer "F.CrtYd")
		)
		(fp_rect
			(start -0.381 0.8382)
			(end 0.381 -0.8382)
			(stroke
				(width 0)
				(type default)
			)
			(fill no)
			(layer "F.Fab")
		)
		(pad "1" smd custom
			(at 0 -0.4318 90)
			(size 0.127 0.127)
			(layers "F.Cu" "F.Mask" "F.Paste")
			(net "PMU_BUF_PLTRST#")
			(options
				(clearance outline)
				(anchor circle)
			)
			(primitives
				(gr_poly
					(pts
						(arc
							(start -0.2032 -0.2794)
							(mid -0.239121 -0.264521)
							(end -0.254 -0.2286)
						)
						(arc
							(start -0.254 0.2286)
							(mid -0.239121 0.264521)
							(end -0.2032 0.2794)
						)
						(arc
							(start 0.2032 0.2794)
							(mid 0.239121 0.264521)
							(end 0.254 0.2286)
						)
						(arc
							(start 0.254 -0.2286)
							(mid 0.239121 -0.264521)
							(end 0.2032 -0.2794)
						)
					)
					(width 0)
					(fill yes)
				)
			)
		)
		(pad "2" smd custom
			(at 0 0.4318 90)
			(size 0.127 0.127)
			(layers "F.Cu" "F.Mask" "F.Paste")
			(net "PCIE_RESET#")
			(options
				(clearance outline)
				(anchor circle)
			)
			(primitives
				(gr_poly
					(pts
						(arc
							(start -0.2032 -0.2794)
							(mid -0.239121 -0.264521)
							(end -0.254 -0.2286)
						)
						(arc
							(start -0.254 0.2286)
							(mid -0.239121 0.264521)
							(end -0.2032 0.2794)
						)
						(arc
							(start 0.2032 0.2794)
							(mid 0.239121 0.264521)
							(end 0.254 0.2286)
						)
						(arc
							(start 0.254 -0.2286)
							(mid 0.239121 -0.264521)
							(end 0.2032 -0.2794)
						)
					)
					(width 0)
					(fill yes)
				)
			)
		)
	)
	(footprint ""
		(layer "F.Cu")
		(at 200.4822 -26.162 -90)
		(property "Reference" "PC183"
			(at 0 0 270)
			(layer "F.SilkS")
			(hide yes)
			(effects
				(font
					(size 1.27 1.27)
				)
			)
		)
		(property "Value" "SC47U16V0MX-GP"
			(at -2.3368 -3.5052 270)
			(unlocked yes)
			(layer "F.Fab")
			(hide yes)
			(effects
				(font
					(size 1.016 1.016)
					(thickness 0.1524)
				)
			)
		)
		(property "Device Type" "C1210H107"
			(at -2.3368 -5.0292 270)
			(unlocked yes)
			(layer "F.Fab")
			(hide yes)
			(effects
				(font
					(size 1.016 1.016)
					(thickness 0.1524)
				)
			)
		)
		(duplicate_pad_numbers_are_jumpers no)
		(fp_rect
			(start -1.4986 1.9685)
			(end 1.4986 -1.9685)
			(stroke
				(width 0)
				(type default)
			)
			(fill no)
			(layer "F.CrtYd")
		)
		(fp_rect
			(start -1.4986 1.9685)
			(end 1.4986 -1.9685)
			(stroke
				(width 0)
				(type default)
			)
			(fill no)
			(layer "F.Fab")
		)
		(pad "1" smd rect
			(at 0 -1.2446 270)
			(size 2.7432 1.1938)
			(layers "F.Cu" "F.Mask" "F.Paste")
			(net "PVDDR_VIN")
		)
		(pad "2" smd rect
			(at 0 1.2446 270)
			(size 2.7432 1.1938)
			(layers "F.Cu" "F.Mask" "F.Paste")
			(net "GND")
		)
	)
	(footprint ""
		(layer "F.Cu")
		(at 8.1788 -24.1554)
		(property "Reference" "PC90"
			(at 0 0 0)
			(layer "F.SilkS")
			(hide yes)
			(effects
				(font
					(size 1.27 1.27)
				)
			)
		)
		(property "Value" "SC4D7U25V5KX-1-GP"
			(at 0 -4.9022 0)
			(unlocked yes)
			(layer "F.Fab")
			(hide yes)
			(effects
				(font
					(size 1.016 1.016)
					(thickness 0.1524)
				)
			)
		)
		(property "Device Type" "C805H58"
			(at 0 -6.8072 0)
			(unlocked yes)
			(layer "F.Fab")
			(hide yes)
			(effects
				(font
					(size 1.016 1.016)
					(thickness 0.1524)
				)
			)
		)
		(duplicate_pad_numbers_are_jumpers no)
		(fp_line
			(start 0.6096 0)
			(end -0.6096 0)
			(stroke
				(width 0.3048)
				(type default)
			)
			(layer "F.SilkS")
		)
		(fp_poly
			(pts
				(xy -0.9017 1.4351) (xy 0.9017 1.4351) (xy 0.9017 -1.4351) (xy -0.9017 -1.4351)
			)
			(stroke
				(width 0)
				(type default)
			)
			(fill no)
			(layer "F.CrtYd")
		)
		(fp_poly
			(pts
				(xy 0.9017 1.4351) (xy 0.9017 -1.4351) (xy -0.9017 -1.4351) (xy -0.9017 1.4351)
			)
			(stroke
				(width 0)
				(type default)
			)
			(fill no)
			(layer "F.Fab")
		)
		(pad "1" smd rect
			(at 0 -0.8382)
			(size 1.5494 0.9398)
			(layers "F.Cu" "F.Mask" "F.Paste")
			(net "P1V0_VDD")
		)
		(pad "2" smd rect
			(at 0 0.8382)
			(size 1.5494 0.9398)
			(layers "F.Cu" "F.Mask" "F.Paste")
			(net "GND")
		)
	)
)
